(kicad_pcb
	(version 20260206)
	(generator "pcbnew")
	(generator_version "10.0")
	(general
		(thickness 1.6)
		(legacy_teardrops no)
	)
	(paper "A4")
	(title_block
		(title "03242023_DA0F0TMBIJ0_F0T_Motherboard_J_brd_V01_OCP.brd")
		(comment 1 "Grand Teton / footprint 2539 of 6105 (J25), pads 225-291 of 291")
	)
	(layers
		(0 "F.Cu" signal "TOP")
		(4 "In1.Cu" signal "GND")
		(6 "In2.Cu" signal "IN1")
		(8 "In3.Cu" signal "GND1")
		(10 "In4.Cu" signal "IN2")
		(12 "In5.Cu" signal "GND2")
		(14 "In6.Cu" signal "IN3")
		(16 "In7.Cu" signal "GND3")
		(18 "In8.Cu" signal "VCC")
		(20 "In9.Cu" signal "VCC1")
		(22 "In10.Cu" signal "GND4")
		(24 "In11.Cu" signal "IN4")
		(26 "In12.Cu" signal "GND5")
		(28 "In13.Cu" signal "IN5")
		(30 "In14.Cu" signal "GND6")
		(32 "In15.Cu" signal "IN6")
		(34 "In16.Cu" signal "GND7")
		(2 "B.Cu" signal "BOTTOM")
		(9 "F.Adhes" user "F.Adhesive")
		(11 "B.Adhes" user "B.Adhesive")
		(13 "F.Paste" user "Package Geometry/Pastemask Top")
		(15 "B.Paste" user "Package Geometry/Pastemask Bottom")
		(5 "F.SilkS" user "Ref Des/Silkscreen Top")
		(7 "B.SilkS" user "Ref Des/Silkscreen Bottom")
		(1 "F.Mask" user "Board Geometry/Soldermask Top")
		(3 "B.Mask" user "Board Geometry/Soldermask Bottom")
		(17 "Dwgs.User" user "User.Drawings")
		(19 "Cmts.User" user "User.Comments")
		(21 "Eco1.User" user "User.Eco1")
		(23 "Eco2.User" user "User.Eco2")
		(25 "Edge.Cuts" user "Board Geometry/Outline")
		(27 "Margin" user)
		(31 "F.CrtYd" user "Package Geometry/Place Bound Top")
		(29 "B.CrtYd" user "Package Geometry/Place Bound Bottom")
		(35 "F.Fab" user "Ref Des/Assembly Top")
		(33 "B.Fab" user "Ref Des/Assembly Bottom")
	)
	(footprint ""
		(layer "F.Cu")
		(at 168.40708 -258.091686)
		(property "Reference" "J25"
			(at -3.683 -81.702148 0)
			(unlocked yes)
			(layer "F.SilkS")
			(effects
				(font
					(size 0.7874 0.5842)
					(thickness 0.1524)
				)
				(justify left)
			)
		)
		(property "Value" ""
			(at 0 0 0)
			(layer "F.Fab")
			(effects
				(font
					(size 1.27 1.27)
				)
			)
		)
		(duplicate_pad_numbers_are_jumpers no)
		(pad "225" smd rect
			(at 2.050034 9.774936 270)
			(size 0.519938 1.4986)
			(layers "F.Cu" "F.Mask" "F.Paste")
			(net "M_E_CPU1_SB_CA<5>")
		)
		(pad "226" smd rect
			(at 2.050034 10.625074 270)
			(size 0.519938 1.4986)
			(layers "F.Cu" "F.Mask" "F.Paste")
			(net "GND")
		)
		(pad "227" smd rect
			(at 2.050034 11.474958 270)
			(size 0.519938 1.4986)
			(layers "F.Cu" "F.Mask" "F.Paste")
			(net "M_E_CPU1_SB_PAR")
		)
		(pad "228" smd rect
			(at 2.050034 12.325096 270)
			(size 0.519938 1.4986)
			(layers "F.Cu" "F.Mask" "F.Paste")
			(net "GND")
		)
		(pad "229" smd rect
			(at 2.050034 13.17498 270)
			(size 0.519938 1.4986)
			(layers "F.Cu" "F.Mask" "F.Paste")
			(net "M_E_CPU1_SB_CS_N<1>")
		)
		(pad "230" smd rect
			(at 2.050034 14.025118 270)
			(size 0.519938 1.4986)
			(layers "F.Cu" "F.Mask" "F.Paste")
			(net "GND")
		)
		(pad "231" smd rect
			(at 2.050034 14.875002 270)
			(size 0.519938 1.4986)
			(layers "F.Cu" "F.Mask" "F.Paste")
			(net "TP_CHE_CPU1_DIMM1_FRU_5")
		)
		(pad "232" smd rect
			(at 2.050034 15.724886 270)
			(size 0.519938 1.4986)
			(layers "F.Cu" "F.Mask" "F.Paste")
			(net "TP_CHE_CPU1_DIMM1_FRU_6")
		)
		(pad "233" smd rect
			(at 2.050034 16.575024 270)
			(size 0.519938 1.4986)
			(layers "F.Cu" "F.Mask" "F.Paste")
			(net "GND")
		)
		(pad "234" smd rect
			(at 2.050034 17.424908 270)
			(size 0.519938 1.4986)
			(layers "F.Cu" "F.Mask" "F.Paste")
			(net "M_E_CPU1_SB_CB<6>")
		)
		(pad "235" smd rect
			(at 2.050034 18.275046 270)
			(size 0.519938 1.4986)
			(layers "F.Cu" "F.Mask" "F.Paste")
			(net "GND")
		)
		(pad "236" smd rect
			(at 2.050034 19.12493 270)
			(size 0.519938 1.4986)
			(layers "F.Cu" "F.Mask" "F.Paste")
			(net "M_E_CPU1_SB_CB<7>")
		)
		(pad "237" smd rect
			(at 2.050034 19.975068 270)
			(size 0.519938 1.4986)
			(layers "F.Cu" "F.Mask" "F.Paste")
			(net "GND")
		)
		(pad "238" smd rect
			(at 2.050034 20.824952 270)
			(size 0.519938 1.4986)
			(layers "F.Cu" "F.Mask" "F.Paste")
			(net "M_E_CPU1_SB_DQS_DN<4>")
		)
		(pad "239" smd rect
			(at 2.050034 21.67509 270)
			(size 0.519938 1.4986)
			(layers "F.Cu" "F.Mask" "F.Paste")
			(net "M_E_CPU1_SB_DQS_DP<4>")
		)
		(pad "240" smd rect
			(at 2.050034 22.524974 270)
			(size 0.519938 1.4986)
			(layers "F.Cu" "F.Mask" "F.Paste")
			(net "GND")
		)
		(pad "241" smd rect
			(at 2.050034 23.375112 270)
			(size 0.519938 1.4986)
			(layers "F.Cu" "F.Mask" "F.Paste")
			(net "M_E_CPU1_SB_CB<2>")
		)
		(pad "242" smd rect
			(at 2.050034 24.224996 270)
			(size 0.519938 1.4986)
			(layers "F.Cu" "F.Mask" "F.Paste")
			(net "GND")
		)
		(pad "243" smd rect
			(at 2.050034 25.07488 270)
			(size 0.519938 1.4986)
			(layers "F.Cu" "F.Mask" "F.Paste")
			(net "M_E_CPU1_SB_CB<3>")
		)
		(pad "244" smd rect
			(at 2.050034 25.925018 270)
			(size 0.519938 1.4986)
			(layers "F.Cu" "F.Mask" "F.Paste")
			(net "GND")
		)
		(pad "245" smd rect
			(at 2.050034 26.774902 270)
			(size 0.519938 1.4986)
			(layers "F.Cu" "F.Mask" "F.Paste")
			(net "M_E_CPU1_SB_DQ<2>")
		)
		(pad "246" smd rect
			(at 2.050034 27.62504 270)
			(size 0.519938 1.4986)
			(layers "F.Cu" "F.Mask" "F.Paste")
			(net "GND")
		)
		(pad "247" smd rect
			(at 2.050034 28.474924 270)
			(size 0.519938 1.4986)
			(layers "F.Cu" "F.Mask" "F.Paste")
			(net "M_E_CPU1_SB_DQ<3>")
		)
		(pad "248" smd rect
			(at 2.050034 29.325062 270)
			(size 0.519938 1.4986)
			(layers "F.Cu" "F.Mask" "F.Paste")
			(net "GND")
		)
		(pad "249" smd rect
			(at 2.050034 30.174946 270)
			(size 0.519938 1.4986)
			(layers "F.Cu" "F.Mask" "F.Paste")
			(net "M_E_CPU1_SB_DQS_DN<5>")
		)
		(pad "250" smd rect
			(at 2.050034 31.025084 270)
			(size 0.519938 1.4986)
			(layers "F.Cu" "F.Mask" "F.Paste")
			(net "M_E_CPU1_SB_DQS_DP<5>")
		)
		(pad "251" smd rect
			(at 2.050034 31.874968 270)
			(size 0.519938 1.4986)
			(layers "F.Cu" "F.Mask" "F.Paste")
			(net "GND")
		)
		(pad "252" smd rect
			(at 2.050034 32.725106 270)
			(size 0.519938 1.4986)
			(layers "F.Cu" "F.Mask" "F.Paste")
			(net "M_E_CPU1_SB_DQ<6>")
		)
		(pad "253" smd rect
			(at 2.050034 33.57499 270)
			(size 0.519938 1.4986)
			(layers "F.Cu" "F.Mask" "F.Paste")
			(net "GND")
		)
		(pad "254" smd rect
			(at 2.050034 34.425128 270)
			(size 0.519938 1.4986)
			(layers "F.Cu" "F.Mask" "F.Paste")
			(net "M_E_CPU1_SB_DQ<7>")
		)
		(pad "255" smd rect
			(at 2.050034 35.275012 270)
			(size 0.519938 1.4986)
			(layers "F.Cu" "F.Mask" "F.Paste")
			(net "GND")
		)
		(pad "256" smd rect
			(at 2.050034 36.124896 270)
			(size 0.519938 1.4986)
			(layers "F.Cu" "F.Mask" "F.Paste")
			(net "M_E_CPU1_SB_DQ<10>")
		)
		(pad "257" smd rect
			(at 2.050034 36.975034 270)
			(size 0.519938 1.4986)
			(layers "F.Cu" "F.Mask" "F.Paste")
			(net "GND")
		)
		(pad "258" smd rect
			(at 2.050034 37.824918 270)
			(size 0.519938 1.4986)
			(layers "F.Cu" "F.Mask" "F.Paste")
			(net "M_E_CPU1_SB_DQ<11>")
		)
		(pad "259" smd rect
			(at 2.050034 38.675056 270)
			(size 0.519938 1.4986)
			(layers "F.Cu" "F.Mask" "F.Paste")
			(net "GND")
		)
		(pad "260" smd rect
			(at 2.050034 39.52494 270)
			(size 0.519938 1.4986)
			(layers "F.Cu" "F.Mask" "F.Paste")
			(net "M_E_CPU1_SB_DQS_DN<6>")
		)
		(pad "261" smd rect
			(at 2.050034 40.375078 270)
			(size 0.519938 1.4986)
			(layers "F.Cu" "F.Mask" "F.Paste")
			(net "M_E_CPU1_SB_DQS_DP<6>")
		)
		(pad "262" smd rect
			(at 2.050034 41.224962 270)
			(size 0.519938 1.4986)
			(layers "F.Cu" "F.Mask" "F.Paste")
			(net "GND")
		)
		(pad "263" smd rect
			(at 2.050034 42.0751 270)
			(size 0.519938 1.4986)
			(layers "F.Cu" "F.Mask" "F.Paste")
			(net "M_E_CPU1_SB_DQ<14>")
		)
		(pad "264" smd rect
			(at 2.050034 42.924984 270)
			(size 0.519938 1.4986)
			(layers "F.Cu" "F.Mask" "F.Paste")
			(net "GND")
		)
		(pad "265" smd rect
			(at 2.050034 43.775122 270)
			(size 0.519938 1.4986)
			(layers "F.Cu" "F.Mask" "F.Paste")
			(net "M_E_CPU1_SB_DQ<15>")
		)
		(pad "266" smd rect
			(at 2.050034 44.625006 270)
			(size 0.519938 1.4986)
			(layers "F.Cu" "F.Mask" "F.Paste")
			(net "GND")
		)
		(pad "267" smd rect
			(at 2.050034 45.47489 270)
			(size 0.519938 1.4986)
			(layers "F.Cu" "F.Mask" "F.Paste")
			(net "M_E_CPU1_SB_DQ<18>")
		)
		(pad "268" smd rect
			(at 2.050034 46.325028 270)
			(size 0.519938 1.4986)
			(layers "F.Cu" "F.Mask" "F.Paste")
			(net "GND")
		)
		(pad "269" smd rect
			(at 2.050034 47.174912 270)
			(size 0.519938 1.4986)
			(layers "F.Cu" "F.Mask" "F.Paste")
			(net "M_E_CPU1_SB_DQ<19>")
		)
		(pad "270" smd rect
			(at 2.050034 48.02505 270)
			(size 0.519938 1.4986)
			(layers "F.Cu" "F.Mask" "F.Paste")
			(net "GND")
		)
		(pad "271" smd rect
			(at 2.050034 48.874934 270)
			(size 0.519938 1.4986)
			(layers "F.Cu" "F.Mask" "F.Paste")
			(net "M_E_CPU1_SB_DQS_DN<7>")
		)
		(pad "272" smd rect
			(at 2.050034 49.725072 270)
			(size 0.519938 1.4986)
			(layers "F.Cu" "F.Mask" "F.Paste")
			(net "M_E_CPU1_SB_DQS_DP<7>")
		)
		(pad "273" smd rect
			(at 2.050034 50.574956 270)
			(size 0.519938 1.4986)
			(layers "F.Cu" "F.Mask" "F.Paste")
			(net "GND")
		)
		(pad "274" smd rect
			(at 2.050034 51.425094 270)
			(size 0.519938 1.4986)
			(layers "F.Cu" "F.Mask" "F.Paste")
			(net "M_E_CPU1_SB_DQ<22>")
		)
		(pad "275" smd rect
			(at 2.050034 52.274978 270)
			(size 0.519938 1.4986)
			(layers "F.Cu" "F.Mask" "F.Paste")
			(net "GND")
		)
		(pad "276" smd rect
			(at 2.050034 53.125116 270)
			(size 0.519938 1.4986)
			(layers "F.Cu" "F.Mask" "F.Paste")
			(net "M_E_CPU1_SB_DQ<23>")
		)
		(pad "277" smd rect
			(at 2.050034 53.975 270)
			(size 0.519938 1.4986)
			(layers "F.Cu" "F.Mask" "F.Paste")
			(net "GND")
		)
		(pad "278" smd rect
			(at 2.050034 54.824884 270)
			(size 0.519938 1.4986)
			(layers "F.Cu" "F.Mask" "F.Paste")
			(net "M_E_CPU1_SB_DQ<26>")
		)
		(pad "279" smd rect
			(at 2.050034 55.675022 270)
			(size 0.519938 1.4986)
			(layers "F.Cu" "F.Mask" "F.Paste")
			(net "GND")
		)
		(pad "280" smd rect
			(at 2.050034 56.524906 270)
			(size 0.519938 1.4986)
			(layers "F.Cu" "F.Mask" "F.Paste")
			(net "M_E_CPU1_SB_DQ<27>")
		)
		(pad "281" smd rect
			(at 2.050034 57.375044 270)
			(size 0.519938 1.4986)
			(layers "F.Cu" "F.Mask" "F.Paste")
			(net "GND")
		)
		(pad "282" smd rect
			(at 2.050034 58.224928 270)
			(size 0.519938 1.4986)
			(layers "F.Cu" "F.Mask" "F.Paste")
			(net "M_E_CPU1_SB_DQS_DN<8>")
		)
		(pad "283" smd rect
			(at 2.050034 59.075066 270)
			(size 0.519938 1.4986)
			(layers "F.Cu" "F.Mask" "F.Paste")
			(net "M_E_CPU1_SB_DQS_DP<8>")
		)
		(pad "284" smd rect
			(at 2.050034 59.92495 270)
			(size 0.519938 1.4986)
			(layers "F.Cu" "F.Mask" "F.Paste")
			(net "GND")
		)
		(pad "285" smd rect
			(at 2.050034 60.775088 270)
			(size 0.519938 1.4986)
			(layers "F.Cu" "F.Mask" "F.Paste")
			(net "M_E_CPU1_SB_DQ<30>")
		)
		(pad "286" smd rect
			(at 2.050034 61.624972 270)
			(size 0.519938 1.4986)
			(layers "F.Cu" "F.Mask" "F.Paste")
			(net "GND")
		)
		(pad "287" smd rect
			(at 2.050034 62.47511 270)
			(size 0.519938 1.4986)
			(layers "F.Cu" "F.Mask" "F.Paste")
			(net "M_E_CPU1_SB_DQ<31>")
		)
		(pad "288" smd rect
			(at 2.050034 63.324994 270)
			(size 0.519938 1.4986)
			(layers "F.Cu" "F.Mask" "F.Paste")
			(net "GND")
		)
		(pad "G1" thru_hole oval
			(at 0 -68.97497)
			(size 2.8194 1.5748)
			(drill oval 2.4384 1.1938)
			(layers "*.Cu" "*.Mask")
			(remove_unused_layers no)
			(net "GND")
			(clearance 0.127)
			(thermal_gap 0.127)
		)
		(pad "G2" thru_hole oval
			(at 0 3.875024)
			(size 2.8194 1.5748)
			(drill oval 2.4384 1.1938)
			(layers "*.Cu" "*.Mask")
			(remove_unused_layers no)
			(net "GND")
			(clearance 0.127)
			(thermal_gap 0.127)
		)
		(pad "G3" thru_hole oval
			(at 0 68.97497)
			(size 2.8194 1.5748)
			(drill oval 2.4384 1.1938)
			(layers "*.Cu" "*.Mask")
			(remove_unused_layers no)
			(net "GND")
			(clearance 0.127)
			(thermal_gap 0.127)
		)
	)
)
